(kicad_pcb
	(version 20241229)
	(generator "pcbnew")
	(generator_version "9.0")
	(general
		(thickness 1.63)
		(legacy_teardrops no)
	)
	(paper "A4")
	(title_block
		(title "CM4 Baseboard")
		(date "2026-01-05")
		(rev "1.1.1")
		(company "Antmicro Ltd")
		(comment 1 "www.antmicro.com")
		(comment 9 "footprints 41-45 of 506")
	)
	(layers
		(0 "F.Cu" signal)
		(4 "In1.Cu" power)
		(6 "In2.Cu" power)
		(8 "In3.Cu" signal)
		(10 "In4.Cu" signal)
		(2 "B.Cu" signal)
		(9 "F.Adhes" user "F.Adhesive")
		(11 "B.Adhes" user "B.Adhesive")
		(13 "F.Paste" user)
		(15 "B.Paste" user)
		(5 "F.SilkS" user "F.Silkscreen")
		(7 "B.SilkS" user "B.Silkscreen")
		(1 "F.Mask" user)
		(3 "B.Mask" user)
		(17 "Dwgs.User" user "User.Drawings")
		(19 "Cmts.User" user "User.Comments")
		(21 "Eco1.User" user "User.Eco1")
		(23 "Eco2.User" user "User.Eco2")
		(25 "Edge.Cuts" user)
		(27 "Margin" user)
		(31 "F.CrtYd" user "F.Courtyard")
		(29 "B.CrtYd" user "B.Courtyard")
		(35 "F.Fab" user)
		(33 "B.Fab" user)
	)
	(footprint "antmicro-footprints:SOT-523"
		(layer "F.Cu")
		(at 98.217962 130.0415 -90)
		(property "Reference" "Q901"
			(at 1.265 0.85 180)
			(layer "F.SilkS")
			(effects
				(font
					(size 0.7 0.7)
					(thickness 0.15)
				)
				(justify right bottom)
			)
		)
		(property "Value" "PJE138K"
			(at 0.1 1.824 90)
			(layer "F.Fab")
			(effects
				(font
					(size 0.7 0.7)
					(thickness 0.15)
				)
				(justify right bottom)
			)
		)
		(property "Datasheet" "https://www.mouser.com/datasheet/2/1057/PJE138K-1876698.pdf"
			(at 0 0 270)
			(layer "F.Fab")
			(hide yes)
			(effects
				(font
					(size 1.27 1.27)
					(thickness 0.15)
				)
			)
		)
		(property "MPN" "PJE138K_R1_00001"
			(at 0 0 270)
			(unlocked yes)
			(layer "F.Fab")
			(hide yes)
			(effects
				(font
					(size 1 1)
					(thickness 0.15)
				)
			)
		)
		(property "Manufacturer" "PANJIT"
			(at 0 0 270)
			(unlocked yes)
			(layer "F.Fab")
			(hide yes)
			(effects
				(font
					(size 1 1)
					(thickness 0.15)
				)
			)
		)
		(property "Author" "Antmicro"
			(at 0 0 270)
			(unlocked yes)
			(layer "F.Fab")
			(hide yes)
			(effects
				(font
					(size 1 1)
					(thickness 0.15)
				)
			)
		)
		(property "License" "Apache-2.0"
			(at 0 0 270)
			(unlocked yes)
			(layer "F.Fab")
			(hide yes)
			(effects
				(font
					(size 1 1)
					(thickness 0.15)
				)
			)
		)
		(sheetname "/USB/")
		(sheetfile "usb.kicad_sch")
		(attr smd)
		(fp_line
			(start -0.927 -0.051)
			(end -0.927 -0.351)
			(stroke
				(width 0.15)
				(type solid)
			)
			(layer "F.SilkS")
		)
		(fp_line
			(start -0.927 -0.351)
			(end -0.725 -0.551)
			(stroke
				(width 0.15)
				(type solid)
			)
			(layer "F.SilkS")
		)
		(fp_line
			(start -0.725 -0.551)
			(end -0.277 -0.551)
			(stroke
				(width 0.15)
				(type solid)
			)
			(layer "F.SilkS")
		)
		(fp_line
			(start -0.277 -0.551)
			(end -0.277 -0.75)
			(stroke
				(width 0.15)
				(type solid)
			)
			(layer "F.SilkS")
		)
		(fp_circle
			(center -0.9652 0.9652)
			(end -0.9152 0.9652)
			(stroke
				(width 0.15)
				(type solid)
			)
			(fill yes)
			(layer "F.SilkS")
		)
		(fp_line
			(start -1.12 1.15)
			(end 1.1 1.15)
			(stroke
				(width 0.05)
				(type solid)
			)
			(layer "F.CrtYd")
		)
		(fp_line
			(start -1.12 -1.16)
			(end -1.12 1.15)
			(stroke
				(width 0.05)
				(type solid)
			)
			(layer "F.CrtYd")
		)
		(fp_line
			(start -1.12 -1.16)
			(end 1.1 -1.16)
			(stroke
				(width 0.05)
				(type solid)
			)
			(layer "F.CrtYd")
		)
		(fp_line
			(start 1.1 -1.16)
			(end 1.1 1.15)
			(stroke
				(width 0.05)
				(type solid)
			)
			(layer "F.CrtYd")
		)
		(fp_line
			(start 0.8 0.424)
			(end -0.802 0.424)
			(stroke
				(width 0.15)
				(type solid)
			)
			(layer "F.Fab")
		)
		(fp_line
			(start -0.802 -0.276)
			(end -0.802 0.424)
			(stroke
				(width 0.15)
				(type solid)
			)
			(layer "F.Fab")
		)
		(fp_line
			(start -0.652 -0.425)
			(end -0.802 -0.276)
			(stroke
				(width 0.15)
				(type solid)
			)
			(layer "F.Fab")
		)
		(fp_line
			(start 0.8 -0.425)
			(end 0.8 0.424)
			(stroke
				(width 0.15)
				(type solid)
			)
			(layer "F.Fab")
		)
		(fp_line
			(start 0.8 -0.425)
			(end -0.652 -0.425)
			(stroke
				(width 0.15)
				(type solid)
			)
			(layer "F.Fab")
		)
		(fp_circle
			(center -0.9652 0.9652)
			(end -0.9144 0.9652)
			(stroke
				(width 0.15)
				(type solid)
			)
			(fill no)
			(layer "F.Fab")
		)
		(fp_text user "${REFERENCE}"
			(at -1.12 3.824 270)
			(layer "F.Fab")
			(effects
				(font
					(size 0.7 0.7)
					(thickness 0.15)
				)
				(justify left bottom)
			)
		)
		(fp_text user "License: Apache-2.0"
			(at -1.12 5.024 270)
			(layer "F.Fab")
			(effects
				(font
					(size 0.7 0.7)
					(thickness 0.15)
				)
				(justify left bottom)
			)
		)
		(fp_text user "Author: Antmicro"
			(at -1.12 6.224 270)
			(layer "F.Fab")
			(effects
				(font
					(size 0.7 0.7)
					(thickness 0.15)
				)
				(justify left bottom)
			)
		)
		(pad "1" smd rect
			(at -0.5 0.65 270)
			(size 0.4 0.51)
			(layers "F.Cu" "F.Mask" "F.Paste")
			(net 279 "/Compute module/USB.OTGID")
			(pinfunction "G")
			(pintype "input")
		)
		(pad "2" smd rect
			(at 0.498 0.65 270)
			(size 0.4 0.51)
			(layers "F.Cu" "F.Mask" "F.Paste")
			(net 3 "GND")
			(pinfunction "S")
			(pintype "passive")
		)
		(pad "3" smd rect
			(at 0 -0.652 270)
			(size 0.4 0.51)
			(layers "F.Cu" "F.Mask" "F.Paste")
			(net 288 "/USB/USBA_OUT_EN")
			(pinfunction "D")
			(pintype "passive")
		)
	)
	(footprint "antmicro-footprints:LED_0603_1608Metric_G"
		(layer "F.Cu")
		(at 75.567962 148.2665 180)
		(descr "LED SMD 0603 Green")
		(tags "LED SMD 0603 Green")
		(property "Reference" "D201"
			(at -1.35 5.1 0)
			(layer "F.SilkS")
			(effects
				(font
					(size 0.7 0.7)
					(thickness 0.15)
				)
				(justify right bottom)
			)
		)
		(property "Value" "LED_G_0603_KP-1608CGCK"
			(at -0.001 1.599 0)
			(layer "F.Fab")
			(effects
				(font
					(size 0.7 0.7)
					(thickness 0.15)
				)
				(justify right bottom)
			)
		)
		(property "Datasheet" "http://www.kingbright.com/attachments/file/psearch//000/00/00/KP-1608CGCK(Ver.23B).pdf"
			(at 0 0 180)
			(layer "F.Fab")
			(hide yes)
			(effects
				(font
					(size 1.27 1.27)
					(thickness 0.15)
				)
			)
		)
		(property "MPN" "KP-1608CGCK"
			(at 0 0 180)
			(unlocked yes)
			(layer "F.Fab")
			(hide yes)
			(effects
				(font
					(size 1 1)
					(thickness 0.15)
				)
			)
		)
		(property "Manufacturer" "Kingbright"
			(at 0 0 180)
			(unlocked yes)
			(layer "F.Fab")
			(hide yes)
			(effects
				(font
					(size 1 1)
					(thickness 0.15)
				)
			)
		)
		(property "Color" "Green"
			(at 0 0 180)
			(unlocked yes)
			(layer "F.Fab")
			(hide yes)
			(effects
				(font
					(size 1 1)
					(thickness 0.15)
				)
			)
		)
		(property "Author" "Antmicro"
			(at 0 0 180)
			(unlocked yes)
			(layer "F.Fab")
			(hide yes)
			(effects
				(font
					(size 1 1)
					(thickness 0.15)
				)
			)
		)
		(property "License" "Apache-2.0"
			(at 0 0 180)
			(unlocked yes)
			(layer "F.Fab")
			(hide yes)
			(effects
				(font
					(size 1 1)
					(thickness 0.15)
				)
			)
		)
		(sheetname "/Compute module/")
		(sheetfile "compute-module.kicad_sch")
		(attr smd)
		(fp_line
			(start 0.22 0.35)
			(end -0.22 0.35)
			(stroke
				(width 0.15)
				(type solid)
			)
			(layer "F.SilkS")
		)
		(fp_line
			(start 0.22 -0.35)
			(end -0.22 -0.35)
			(stroke
				(width 0.15)
				(type solid)
			)
			(layer "F.SilkS")
		)
		(fp_line
			(start 0.105328 0.201008)
			(end 0.105328 -0.198992)
			(stroke
				(width 0.1)
				(type solid)
			)
			(layer "F.SilkS")
		)
		(fp_line
			(start 0.105328 0.201008)
			(end -0.094672 0.001008)
			(stroke
				(width 0.1)
				(type solid)
			)
			(layer "F.SilkS")
		)
		(fp_line
			(start 0.105328 0.001008)
			(end 0.24 0.001)
			(stroke
				(width 0.1)
				(type solid)
			)
			(layer "F.SilkS")
		)
		(fp_line
			(start -0.094672 0.201008)
			(end -0.094672 -0.198992)
			(stroke
				(width 0.1)
				(type solid)
			)
			(layer "F.SilkS")
		)
		(fp_line
			(start -0.094672 0.001008)
			(end 0.105328 -0.198992)
			(stroke
				(width 0.1)
				(type solid)
			)
			(layer "F.SilkS")
		)
		(fp_line
			(start -0.094672 0.001008)
			(end -0.24 0.001008)
			(stroke
				(width 0.1)
				(type solid)
			)
			(layer "F.SilkS")
		)
		(fp_line
			(start -1.18 -0.319)
			(end -1.18 0.321)
			(stroke
				(width 0.15)
				(type solid)
			)
			(layer "F.SilkS")
		)
		(fp_rect
			(start 1.25 0.65)
			(end -1.25 -0.65)
			(stroke
				(width 0.05)
				(type solid)
			)
			(fill no)
			(layer "F.CrtYd")
		)
		(fp_line
			(start 0.599 0)
			(end 0.201 0)
			(stroke
				(width 0.15)
				(type solid)
			)
			(layer "F.Fab")
		)
		(fp_line
			(start 0.201 0.2)
			(end 0.201 0)
			(stroke
				(width 0.15)
				(type solid)
			)
			(layer "F.Fab")
		)
		(fp_line
			(start 0.201 0)
			(end 0.201 -0.202)
			(stroke
				(width 0.15)
				(type solid)
			)
			(layer "F.Fab")
		)
		(fp_line
			(start 0.201 -0.202)
			(end -0.101 0)
			(stroke
				(width 0.15)
				(type solid)
			)
			(layer "F.Fab")
		)
		(fp_line
			(start -0.101 0)
			(end 0.201 0.2)
			(stroke
				(width 0.15)
				(type solid)
			)
			(layer "F.Fab")
		)
		(fp_line
			(start -0.199 0.2)
			(end -0.199 0.1)
			(stroke
				(width 0.15)
				(type solid)
			)
			(layer "F.Fab")
		)
		(fp_line
			(start -0.199 0)
			(end -0.597 0)
			(stroke
				(width 0.15)
				(type solid)
			)
			(layer "F.Fab")
		)
		(fp_line
			(start -0.199 -0.202)
			(end -0.199 0.1)
			(stroke
				(width 0.15)
				(type solid)
			)
			(layer "F.Fab")
		)
		(fp_rect
			(start 0.848 0.4)
			(end -0.85 -0.402)
			(stroke
				(width 0.15)
				(type solid)
			)
			(fill no)
			(layer "F.Fab")
		)
		(fp_text user "${REFERENCE}"
			(at -1.4224 5.999 180)
			(layer "F.Fab")
			(effects
				(font
					(size 0.7 0.7)
					(thickness 0.15)
				)
				(justify left bottom)
			)
		)
		(fp_text user "Author: Antmicro"
			(at -1.4224 4.799 180)
			(layer "F.Fab")
			(effects
				(font
					(size 0.7 0.7)
					(thickness 0.15)
				)
				(justify left bottom)
			)
		)
		(fp_text user "License: Apache-2.0"
			(at -1.4224 3.599 180)
			(layer "F.Fab")
			(effects
				(font
					(size 0.7 0.7)
					(thickness 0.15)
				)
				(justify left bottom)
			)
		)
		(pad "1" smd roundrect
			(at -0.7 0)
			(size 0.8 1)
			(layers "F.Cu" "F.Mask" "F.Paste")
			(roundrect_rratio 0.2)
			(net 445 "Net-(D201-C)")
			(pinfunction "C")
			(pintype "passive")
		)
		(pad "2" smd roundrect
			(at 0.7 0)
			(size 0.8 1)
			(layers "F.Cu" "F.Mask" "F.Paste")
			(roundrect_rratio 0.2)
			(net 10 "+5V")
			(pinfunction "A")
			(pintype "passive")
		)
	)
	(footprint "antmicro-footprints:Conn_JST_SH_1x4_SM04B-SRSS-TB-LF-SN"
		(layer "F.Cu")
		(at 132.317962 114.6165 180)
		(property "Reference" "J803"
			(at -4.56 2.73 90)
			(layer "F.SilkS")
			(effects
				(font
					(size 0.7 0.7)
					(thickness 0.15)
				)
				(justify right bottom)
			)
		)
		(property "Value" "JST_SH_1x4_SM04B-SRSS-TB-LF-SN"
			(at 0 3.9 0)
			(layer "F.Fab")
			(effects
				(font
					(size 0.7 0.7)
					(thickness 0.15)
				)
				(justify right bottom)
			)
		)
		(property "Datasheet" "https://www.jst-mfg.com/product/pdf/eng/eSH.pdf"
			(at 0 0 180)
			(layer "F.Fab")
			(hide yes)
			(effects
				(font
					(size 1.27 1.27)
					(thickness 0.15)
				)
			)
		)
		(property "MPN" "SM04B-SRSS-TB(LF)(SN)"
			(at 0 0 180)
			(unlocked yes)
			(layer "F.Fab")
			(hide yes)
			(effects
				(font
					(size 1 1)
					(thickness 0.15)
				)
			)
		)
		(property "Manufacturer" "JST Automotive Connectors"
			(at 0 0 180)
			(unlocked yes)
			(layer "F.Fab")
			(hide yes)
			(effects
				(font
					(size 1 1)
					(thickness 0.15)
				)
			)
		)
		(property "Author" "Antmicro"
			(at 0 0 180)
			(unlocked yes)
			(layer "F.Fab")
			(hide yes)
			(effects
				(font
					(size 1 1)
					(thickness 0.15)
				)
			)
		)
		(property "License" "Apache-2.0"
			(at 0 0 180)
			(unlocked yes)
			(layer "F.Fab")
			(hide yes)
			(effects
				(font
					(size 1 1)
					(thickness 0.15)
				)
			)
		)
		(sheetname "/Peripherals/")
		(sheetfile "peripherals.kicad_sch")
		(attr smd)
		(fp_line
			(start 3.2 -2)
			(end 3.2 0.6)
			(stroke
				(width 0.15)
				(type solid)
			)
			(layer "F.SilkS")
		)
		(fp_line
			(start 2 -2)
			(end 3.2 -2)
			(stroke
				(width 0.15)
				(type solid)
			)
			(layer "F.SilkS")
		)
		(fp_line
			(start -2 2.6)
			(end 2 2.6)
			(stroke
				(width 0.15)
				(type solid)
			)
			(layer "F.SilkS")
		)
		(fp_line
			(start -2 -2)
			(end -3.2 -2)
			(stroke
				(width 0.15)
				(type solid)
			)
			(layer "F.SilkS")
		)
		(fp_line
			(start -3.2 -2)
			(end -3.2 0.6)
			(stroke
				(width 0.15)
				(type solid)
			)
			(layer "F.SilkS")
		)
		(fp_circle
			(center -2.1 -2.5)
			(end -2.05 -2.5)
			(stroke
				(width 0.15)
				(type solid)
			)
			(fill yes)
			(layer "F.SilkS")
		)
		(fp_rect
			(start -3.65 -3.14)
			(end 3.65 2.9)
			(stroke
				(width 0.05)
				(type solid)
			)
			(fill no)
			(layer "F.CrtYd")
		)
		(fp_rect
			(start -3 -2.475)
			(end 3 2.475)
			(stroke
				(width 0.15)
				(type solid)
			)
			(fill no)
			(layer "F.Fab")
		)
		(fp_text user "License: Apache-2.0"
			(at -4 5.88 180)
			(layer "F.Fab")
			(effects
				(font
					(size 0.7 0.7)
					(thickness 0.15)
				)
				(justify left bottom)
			)
		)
		(fp_text user "${REFERENCE}"
			(at -4 8.28 180)
			(layer "F.Fab")
			(effects
				(font
					(size 0.7 0.7)
					(thickness 0.15)
				)
				(justify left bottom)
			)
		)
		(fp_text user "Author: Antmicro"
			(at -4 7.08 180)
			(layer "F.Fab")
			(effects
				(font
					(size 0.7 0.7)
					(thickness 0.15)
				)
				(justify left bottom)
			)
		)
		(pad "1" smd roundrect
			(at -1.5 -2.12)
			(size 0.6 1.55)
			(layers "F.Cu" "F.Mask" "F.Paste")
			(roundrect_rratio 0.25)
			(net 3 "GND")
			(pintype "passive")
		)
		(pad "2" smd roundrect
			(at -0.5 -2.12)
			(size 0.6 1.55)
			(layers "F.Cu" "F.Mask" "F.Paste")
			(roundrect_rratio 0.25)
			(net 317 "/Peripherals/VLED")
			(pintype "passive")
		)
		(pad "3" smd roundrect
			(at 0.5 -2.12)
			(size 0.6 1.55)
			(layers "F.Cu" "F.Mask" "F.Paste")
			(roundrect_rratio 0.25)
			(net 143 "/CSI/I_{2}C1.SDA")
			(pintype "passive")
		)
		(pad "4" smd roundrect
			(at 1.5 -2.12)
			(size 0.6 1.55)
			(layers "F.Cu" "F.Mask" "F.Paste")
			(roundrect_rratio 0.25)
			(net 142 "/CSI/I_{2}C1.SCL")
			(pintype "passive")
		)
		(pad "MP" smd roundrect
			(at -2.8 1.755 180)
			(size 1.2 1.8)
			(layers "F.Cu" "F.Mask" "F.Paste")
			(roundrect_rratio 0.25)
			(net 3 "GND")
			(pintype "passive")
		)
		(pad "MP" smd roundrect
			(at 2.8 1.755 180)
			(size 1.2 1.8)
			(layers "F.Cu" "F.Mask" "F.Paste")
			(roundrect_rratio 0.25)
			(net 3 "GND")
			(pintype "passive")
		)
	)
	(footprint "antmicro-footprints:TP_SMD_0.75mm"
		(layer "F.Cu")
		(at 99.777962 119.539)
		(property "Reference" "TP909"
			(at 27.995 26.2225 90)
			(layer "F.SilkS")
			(effects
				(font
					(size 0.7 0.7)
					(thickness 0.15)
				)
				(justify left bottom)
			)
		)
		(property "Value" "TP_0.75mm_SMD"
			(at 0 1.2 0)
			(layer "F.Fab")
			(effects
				(font
					(size 0.7 0.7)
					(thickness 0.15)
				)
				(justify left bottom)
			)
		)
		(property "MPN" ""
			(at 0 0 0)
			(unlocked yes)
			(layer "F.Fab")
			(hide yes)
			(effects
				(font
					(size 1 1)
					(thickness 0.15)
				)
			)
		)
		(property "Manufacturer" ""
			(at 0 0 0)
			(unlocked yes)
			(layer "F.Fab")
			(hide yes)
			(effects
				(font
					(size 1 1)
					(thickness 0.15)
				)
			)
		)
		(property "Author" "Antmicro"
			(at 0 0 0)
			(unlocked yes)
			(layer "F.Fab")
			(hide yes)
			(effects
				(font
					(size 1 1)
					(thickness 0.15)
				)
			)
		)
		(property "License" "Apache-2.0"
			(at 0 0 0)
			(unlocked yes)
			(layer "F.Fab")
			(hide yes)
			(effects
				(font
					(size 1 1)
					(thickness 0.15)
				)
			)
		)
		(sheetname "/USB/")
		(sheetfile "usb.kicad_sch")
		(attr exclude_from_pos_files exclude_from_bom)
		(fp_circle
			(center 0 0)
			(end 0.475 0)
			(stroke
				(width 0.05)
				(type default)
			)
			(fill no)
			(layer "F.CrtYd")
		)
		(fp_text user "License: Apache-2.0"
			(at -0.4 5.101 0)
			(layer "F.Fab")
			(effects
				(font
					(size 0.7 0.7)
					(thickness 0.15)
				)
				(justify left bottom)
			)
		)
		(fp_text user "Author: Antmicro"
			(at -0.4 3.901 0)
			(layer "F.Fab")
			(effects
				(font
					(size 0.7 0.7)
					(thickness 0.15)
				)
				(justify left bottom)
			)
		)
		(fp_text user "${REFERENCE}"
			(at -0.4 2.7 0)
			(layer "F.Fab")
			(effects
				(font
					(size 0.7 0.7)
					(thickness 0.15)
				)
				(justify left bottom)
			)
		)
		(pad "1" smd circle
			(at 0 0)
			(size 0.75 0.75)
			(layers "F.Cu" "F.Mask")
			(net 434 "Net-(U906-PORT)")
			(pinfunction "1")
			(pintype "passive")
		)
	)
	(footprint "antmicro-footprints:TP_SMD_0.75mm"
		(layer "F.Cu")
		(at 108 154.825)
		(property "Reference" "TP217"
			(at 0.45 0.475 0)
			(layer "F.SilkS")
			(effects
				(font
					(size 0.7 0.7)
					(thickness 0.15)
				)
				(justify left bottom)
			)
		)
		(property "Value" "TP_0.75mm_SMD"
			(at 0 1.2 0)
			(layer "F.Fab")
			(effects
				(font
					(size 0.7 0.7)
					(thickness 0.15)
				)
				(justify left bottom)
			)
		)
		(property "MPN" ""
			(at 0 0 0)
			(unlocked yes)
			(layer "F.Fab")
			(hide yes)
			(effects
				(font
					(size 1 1)
					(thickness 0.15)
				)
			)
		)
		(property "Manufacturer" ""
			(at 0 0 0)
			(unlocked yes)
			(layer "F.Fab")
			(hide yes)
			(effects
				(font
					(size 1 1)
					(thickness 0.15)
				)
			)
		)
		(property "Author" "Antmicro"
			(at 0 0 0)
			(unlocked yes)
			(layer "F.Fab")
			(hide yes)
			(effects
				(font
					(size 1 1)
					(thickness 0.15)
				)
			)
		)
		(property "License" "Apache-2.0"
			(at 0 0 0)
			(unlocked yes)
			(layer "F.Fab")
			(hide yes)
			(effects
				(font
					(size 1 1)
					(thickness 0.15)
				)
			)
		)
		(sheetname "/Compute module/")
		(sheetfile "compute-module.kicad_sch")
		(attr exclude_from_pos_files exclude_from_bom)
		(fp_circle
			(center 0 0)
			(end 0.475 0)
			(stroke
				(width 0.05)
				(type default)
			)
			(fill no)
			(layer "F.CrtYd")
		)
		(fp_text user "Author: Antmicro"
			(at -0.4 3.901 0)
			(layer "F.Fab")
			(effects
				(font
					(size 0.7 0.7)
					(thickness 0.15)
				)
				(justify left bottom)
			)
		)
		(fp_text user "${REFERENCE}"
			(at -0.4 2.7 0)
			(layer "F.Fab")
			(effects
				(font
					(size 0.7 0.7)
					(thickness 0.15)
				)
				(justify left bottom)
			)
		)
		(fp_text user "License: Apache-2.0"
			(at -0.4 5.101 0)
			(layer "F.Fab")
			(effects
				(font
					(size 0.7 0.7)
					(thickness 0.15)
				)
				(justify left bottom)
			)
		)
		(pad "1" smd circle
			(at 0 0)
			(size 0.75 0.75)
			(layers "F.Cu" "F.Mask")
			(net 260 "/Compute module/Pf_5V.CEC")
			(pinfunction "1")
			(pintype "passive")
		)
	)
)
